FILE_TYPE = MACRO_DRAWING;
SET COLOR_WIRE YELLOW;
SET COLOR_PROP MONO;
SET COLOR_DOT WHITE;
SET COLOR_ARC YELLOW;
SET COLOR_BODY GREEN;
SET COLOR_NOTE MONO;
SET PROP_DISPLAY VALUE;
SET PAGE_NUMBER P174;
FORCEADD INTEL_CORP_BPAGE..1
(12800 300);
FORCEPROP 1 LAST CDS_CON_LAST_MODIFIED Fri Jun 16 17:49:04 2017
J 0
(11375 625);
DISPLAY 1.382979 (11375 625);
PAINT GREEN (11375 625);
DISPLAY INVISIBLE (11375 625);
FORCEPROP 1 LAST CUSTOM_TXT_CDS <CURRENT_DESIGN_SHEET> OF <TOTAL_DESIGN_SHEETS>
J 0
(12300 325);
PAINT ORANGE (12300 325);
FORCEPROP 2 LAST CUSTOM_TXT_CDS <XR_PAGE_TITLE>
J 0
(4910 5550);
DISPLAY 0.638298 (4910 5550);
PAINT PINK (4910 5550);
DISPLAY INVISIBLE (4910 5550);
FORCEPROP 2 LAST CUSTOM_TXT_CDS <CON_LAST_MODIFIED>
J 0
(8800 375);
DISPLAY 1.382979 (8800 375);
PAINT ORANGE (8800 375);
FORCEPROP 1 LAST SCH_TITLE MINI_SAS (2/2)
J 0
(4850 350);
DISPLAY 1.212766 (4850 350);
PAINT YELLOW (4850 350);
FORCEPROP 2 LAST PAGE_BORDER TRUE
J 0
(4910 5550);
DISPLAY 0.872340 (4910 5550);
PAINT PINK (4910 5550);
DISPLAY INVISIBLE (4910 5550);
FORCEPROP 2 LAST CDS_LIB mstr_symbols
J 0
(12800 300);
DISPLAY 1.382979 (12800 300);
PAINT ORANGE (12800 300);
DISPLAY INVISIBLE (12800 300);
FORCEPROP 1 LAST COMMENT_BODY TRUE
J 0
(12812 312);
DISPLAY 0.617021 (12812 312);
PAINT PEACH (12812 312);
DISPLAY INVISIBLE (12812 312);
FORCEPROP 2 LAST CDS_XR_PAGE_TITLE CR-174 : @BASEBOARD_FAB2_LIB.BASEBOARD_FAB2(SCH_1):PAGE174
J 0
(4910 5550);
DISPLAY 0.638298 (4910 5550);
PAINT PINK (4910 5550);
DISPLAY INVISIBLE (4910 5550);
WIRE 3 682 (12400 850)(12400 4950);
WIRE 3 682 (5250 850)(12400 850);
WIRE 3 682 (12400 4950)(5250 4950);
WIRE 3 682 (5250 4950)(5250 850);
FORCENOTE
TP FAB3 DELETE MINI-SAS X4 0920
(5250 775) 0;
DISPLAY LEFT (5250 775);
DISPLAY 1.021277 (5250 775);
PAINT RED (5250 775);
QUIT
